# BASEBOARD_FAB2 (Tioga Pass) — schematic netlist excerpt (pin names and nets, part order shuffled) for the footprints in the layout excerpt that follows; sources: Cadence DE-HDL packaged netlist, KiCad conversion of Wiwynn_Tioga_Pass_MB.brd

T1D22  TEST-PAD-12P-1-GP-U  pkg DISCRET-GB1  page 258
  DP  = L12_85OHM_10INCH_DN
  DN  = L12_85OHM_10INCH_DP
  GND(0)  = GND
  GND(1)  = GND
  GND(2)  = GND
  GND(3)  = GND
  GND(4)  = GND
  GND(5)  = GND
  GND(6)  = GND
  GND(7)  = GND
  GND(8)  = GND
  GND(9)  = GND

(kicad_pcb
	(version 20260206)
	(generator "pcbnew")
	(generator_version "10.0")
	(general
		(thickness 1.6)
		(legacy_teardrops no)
	)
	(paper "A4")
	(title_block
		(title "Wiwynn_Tioga_Pass_MB.brd")
		(comment 1 "Tioga Pass / footprints 805-805 of 4770")
	)
	(layers
		(0 "F.Cu" signal "TOP")
		(4 "In1.Cu" signal "L2GND")
		(6 "In2.Cu" signal "L3")
		(8 "In3.Cu" signal "L4GND")
		(10 "In4.Cu" signal "L5")
		(12 "In5.Cu" signal "L6GND")
		(14 "In6.Cu" signal "L7VCC")
		(16 "In7.Cu" signal "L8VCC")
		(18 "In8.Cu" signal "L9GND")
		(20 "In9.Cu" signal "L10")
		(22 "In10.Cu" signal "L11GND")
		(24 "In11.Cu" signal "L12")
		(26 "In12.Cu" signal "L13GND")
		(2 "B.Cu" signal "BOTTOM")
		(9 "F.Adhes" user "F.Adhesive")
		(11 "B.Adhes" user "B.Adhesive")
		(13 "F.Paste" user "Package Geometry/Pastemask Top")
		(15 "B.Paste" user "Package Geometry/Pastemask Bottom")
		(5 "F.SilkS" user "Ref Des/Silkscreen Top")
		(7 "B.SilkS" user "Ref Des/Silkscreen Bottom")
		(1 "F.Mask" user "Board Geometry/Soldermask Top")
		(3 "B.Mask" user "Board Geometry/Soldermask Bottom")
		(17 "Dwgs.User" user "User.Drawings")
		(19 "Cmts.User" user "User.Comments")
		(21 "Eco1.User" user "User.Eco1")
		(23 "Eco2.User" user "User.Eco2")
		(25 "Edge.Cuts" user "Board Geometry/Outline")
		(27 "Margin" user)
		(31 "F.CrtYd" user "Package Geometry/Place Bound Top")
		(29 "B.CrtYd" user "Package Geometry/Place Bound Bottom")
		(35 "F.Fab" user "Ref Des/Assembly Top")
		(33 "B.Fab" user "Ref Des/Assembly Bottom")
	)
	(footprint ""
		(layer "F.Cu")
		(at 308.874414 -164.908992 90)
		(property "Reference" "T1D22"
			(at 0 0 90)
			(layer "F.SilkS")
			(hide yes)
			(effects
				(font
					(size 1.27 1.27)
				)
			)
		)
		(property "Value" "*"
			(at -3.4036 -4.46405 90)
			(unlocked yes)
			(layer "F.Fab")
			(hide yes)
			(effects
				(font
					(size 0.889 0.889)
					(thickness 0.1524)
				)
			)
		)
		(property "Device Type" "TEST-PAD-12P-1-GP-U_DISCRET-GBA"
			(at -3.4036 -5.98805 90)
			(unlocked yes)
			(layer "F.Fab")
			(hide yes)
			(effects
				(font
					(size 0.889 0.889)
					(thickness 0.1524)
				)
			)
		)
		(duplicate_pad_numbers_are_jumpers no)
		(fp_line
			(start 2.3622 -4.826)
			(end 2.3622 3.4798)
			(stroke
				(width 0.1524)
				(type default)
			)
			(layer "F.SilkS")
		)
		(fp_line
			(start -2.3876 -4.826)
			(end 2.3622 -4.826)
			(stroke
				(width 0.1524)
				(type default)
			)
			(layer "F.SilkS")
		)
		(fp_line
			(start 2.3622 3.4798)
			(end -2.3876 3.4798)
			(stroke
				(width 0.1524)
				(type default)
			)
			(layer "F.SilkS")
		)
		(fp_line
			(start -2.3876 3.4798)
			(end -2.3876 -4.826)
			(stroke
				(width 0.1524)
				(type default)
			)
			(layer "F.SilkS")
		)
		(fp_rect
			(start -2.6416 3.7338)
			(end 2.6162 -5.08)
			(stroke
				(width 0)
				(type default)
			)
			(fill no)
			(layer "F.CrtYd")
		)
		(fp_rect
			(start -2.6416 3.7338)
			(end 2.6162 -5.08)
			(stroke
				(width 0)
				(type default)
			)
			(fill no)
			(layer "F.Fab")
		)
		(pad "1" smd circle
			(at 0.496824 -1.301496 90)
			(size 0.6604 0.6604)
			(layers "F.Cu" "F.Mask" "F.Paste")
			(net "L12_85OHM_10INCH_DN")
		)
		(pad "2" smd circle
			(at -0.503936 -1.301496 90)
			(size 0.6604 0.6604)
			(layers "F.Cu" "F.Mask" "F.Paste")
			(net "L12_85OHM_10INCH_DP")
		)
		(pad "3" smd custom
			(at -0.00889 0.370078 90)
			(size 0.74295 0.74295)
			(layers "F.Cu" "F.Mask" "F.Paste")
			(net "GND")
			(options
				(clearance outline)
				(anchor circle)
			)
			(primitives
				(gr_poly
					(pts
						(xy -2.1209 1.4859) (xy 2.1209 1.4859) (xy 2.1209 -1.4859) (xy 1.08585 -1.4859) (xy 1.08585 -0.4699)
						(xy -1.08585 -0.4699) (xy -1.08585 -1.4859) (xy -2.1209 -1.4859)
					)
					(width 0)
					(fill yes)
				)
			)
		)
		(pad "4" thru_hole circle
			(at 1.266444 -3.851656 90)
			(size 1.4478 1.4478)
			(drill 1.0414)
			(layers "*.Cu" "*.Mask")
			(remove_unused_layers no)
			(net "GND")
			(clearance 0.1524)
			(thermal_gap 0.1524)
		)
		(pad "5" thru_hole circle
			(at -1.273556 -3.851656 90)
			(size 1.4478 1.4478)
			(drill 1.0414)
			(layers "*.Cu" "*.Mask")
			(remove_unused_layers no)
			(net "GND")
			(clearance 0.1524)
			(thermal_gap 0.1524)
		)
		(pad "6" thru_hole circle
			(at 1.266444 2.498344 90)
			(size 1.4478 1.4478)
			(drill 1.0414)
			(layers "*.Cu" "*.Mask")
			(remove_unused_layers no)
			(net "GND")
			(clearance 0.1524)
			(thermal_gap 0.1524)
		)
		(pad "7" thru_hole circle
			(at -1.273556 2.498344 90)
			(size 1.4478 1.4478)
			(drill 1.0414)
			(layers "*.Cu" "*.Mask")
			(remove_unused_layers no)
			(net "GND")
			(clearance 0.1524)
			(thermal_gap 0.1524)
		)
		(pad "8" thru_hole circle
			(at 1.27 -0.4572 90)
			(size 0.7112 0.7112)
			(drill 0.4064)
			(layers "*.Cu" "*.Mask")
			(remove_unused_layers no)
			(net "GND")
			(clearance 0.1016)
			(thermal_gap 0.1016)
		)
		(pad "9" thru_hole circle
			(at 1.27 0.762 90)
			(size 0.7112 0.7112)
			(drill 0.4064)
			(layers "*.Cu" "*.Mask")
			(remove_unused_layers no)
			(net "GND")
			(clearance 0.1016)
			(thermal_gap 0.1016)
		)
		(pad "10" thru_hole circle
			(at -0.0254 0.762 90)
			(size 0.7112 0.7112)
			(drill 0.4064)
			(layers "*.Cu" "*.Mask")
			(remove_unused_layers no)
			(net "GND")
			(clearance 0.1016)
			(thermal_gap 0.1016)
		)
		(pad "11" thru_hole circle
			(at -1.27 0.762 90)
			(size 0.7112 0.7112)
			(drill 0.4064)
			(layers "*.Cu" "*.Mask")
			(remove_unused_layers no)
			(net "GND")
			(clearance 0.1016)
			(thermal_gap 0.1016)
		)
		(pad "12" thru_hole circle
			(at -1.27 -0.4572 90)
			(size 0.7112 0.7112)
			(drill 0.4064)
			(layers "*.Cu" "*.Mask")
			(remove_unused_layers no)
			(net "GND")
			(clearance 0.1016)
			(thermal_gap 0.1016)
		)
	)
)
